# T6G (Grand Teton) — schematic netlist excerpt (pin names and nets, part order shuffled) for the footprints in the layout excerpt that follows; sources: Cadence DE-HDL packaged netlist, KiCad conversion of 04192023_DAF0TMB3IC0_F0TG_MB_C_brd_V02_OCP.brd

C2251  Q_CAP  22UF 4V 20% X6S  pkg C0402  page 69 : A = PVDDCR_CPU1_P0 ; B = GND
PC6635_2  Q_CAP  22UF 16V 20% X6S  pkg C0805  page 365 : A = SW_P12V_AUX_P0V9_RETIMER_CPU1_FLT ; B = GND
PR6501  Q_RES  0 5% CHIP  pkg 0402LF  page 360 : A = P3V3_AUX ; B = P1V8_RETIMER_CPU0_VCC

(kicad_pcb
	(version 20260206)
	(generator "pcbnew")
	(generator_version "10.0")
	(general
		(thickness 1.6)
		(legacy_teardrops no)
	)
	(paper "A4")
	(title_block
		(title "04192023_DAF0TMB3IC0_F0TG_MB_C_brd_V02_OCP.brd")
		(comment 1 "Grand Teton / footprints 6502-6504 of 8354")
	)
	(layers
		(0 "F.Cu" signal "TOP")
		(4 "In1.Cu" signal "GND")
		(6 "In2.Cu" signal "IN1")
		(8 "In3.Cu" signal "GND1")
		(10 "In4.Cu" signal "IN2")
		(12 "In5.Cu" signal "GND2")
		(14 "In6.Cu" signal "IN3")
		(16 "In7.Cu" signal "GND3")
		(18 "In8.Cu" signal "VCC")
		(20 "In9.Cu" signal "VCC1")
		(22 "In10.Cu" signal "GND4")
		(24 "In11.Cu" signal "IN4")
		(26 "In12.Cu" signal "GND5")
		(28 "In13.Cu" signal "IN5")
		(30 "In14.Cu" signal "GND6")
		(32 "In15.Cu" signal "IN6")
		(34 "In16.Cu" signal "GND7")
		(2 "B.Cu" signal "BOTTOM")
		(9 "F.Adhes" user "F.Adhesive")
		(11 "B.Adhes" user "B.Adhesive")
		(13 "F.Paste" user "Package Geometry/Pastemask Top")
		(15 "B.Paste" user "Package Geometry/Pastemask Bottom")
		(5 "F.SilkS" user "Ref Des/Silkscreen Top")
		(7 "B.SilkS" user "Ref Des/Silkscreen Bottom")
		(1 "F.Mask" user "Board Geometry/Soldermask Top")
		(3 "B.Mask" user "Board Geometry/Soldermask Bottom")
		(17 "Dwgs.User" user "User.Drawings")
		(19 "Cmts.User" user "User.Comments")
		(21 "Eco1.User" user "User.Eco1")
		(23 "Eco2.User" user "User.Eco2")
		(25 "Edge.Cuts" user "Board Geometry/Outline")
		(27 "Margin" user)
		(31 "F.CrtYd" user "Package Geometry/Place Bound Top")
		(29 "B.CrtYd" user "Package Geometry/Place Bound Bottom")
		(35 "F.Fab" user "Ref Des/Assembly Top")
		(33 "B.Fab" user "Ref Des/Assembly Bottom")
	)
	(footprint ""
		(layer "B.Cu")
		(at 372.135654 -269.30731 180)
		(property "Reference" "C2251"
			(at 0 0 0)
			(layer "B.SilkS")
			(hide yes)
			(effects
				(font
					(size 1.27 1.27)
				)
				(justify mirror)
			)
		)
		(property "Value" ""
			(at 0 0 0)
			(layer "B.Fab")
			(effects
				(font
					(size 1.27 1.27)
				)
				(justify mirror)
			)
		)
		(duplicate_pad_numbers_are_jumpers no)
		(fp_line
			(start 0.7874 0.4064)
			(end 0.7874 -0.4064)
			(stroke
				(width 0.1524)
				(type default)
			)
			(layer "B.SilkS")
		)
		(fp_line
			(start 0.7874 -0.4064)
			(end -0.7874 -0.4064)
			(stroke
				(width 0.1524)
				(type default)
			)
			(layer "B.SilkS")
		)
		(fp_line
			(start -0.7874 0.4064)
			(end 0.7874 0.4064)
			(stroke
				(width 0.1524)
				(type default)
			)
			(layer "B.SilkS")
		)
		(fp_line
			(start -0.7874 -0.4064)
			(end -0.7874 0.4064)
			(stroke
				(width 0.1524)
				(type default)
			)
			(layer "B.SilkS")
		)
		(fp_line
			(start 0.67945 0.3048)
			(end 0.67945 -0.305054)
			(stroke
				(width 0.1)
				(type default)
			)
			(layer "B.Fab")
		)
		(fp_line
			(start 0.67945 -0.305054)
			(end 0.12065 -0.305054)
			(stroke
				(width 0.1)
				(type default)
			)
			(layer "B.Fab")
		)
		(fp_line
			(start 0.12065 0.3048)
			(end 0.67945 0.3048)
			(stroke
				(width 0.1)
				(type default)
			)
			(layer "B.Fab")
		)
		(fp_line
			(start 0.12065 0.2794)
			(end 0.12065 0.3048)
			(stroke
				(width 0.1)
				(type default)
			)
			(layer "B.Fab")
		)
		(fp_line
			(start 0.12065 -0.2794)
			(end -0.12065 -0.2794)
			(stroke
				(width 0.1)
				(type default)
			)
			(layer "B.Fab")
		)
		(fp_line
			(start 0.12065 -0.305054)
			(end 0.12065 -0.2794)
			(stroke
				(width 0.1)
				(type default)
			)
			(layer "B.Fab")
		)
		(fp_line
			(start -0.120396 0.3048)
			(end -0.120396 0.2794)
			(stroke
				(width 0.1)
				(type default)
			)
			(layer "B.Fab")
		)
		(fp_line
			(start -0.120396 0.2794)
			(end 0.12065 0.2794)
			(stroke
				(width 0.1)
				(type default)
			)
			(layer "B.Fab")
		)
		(fp_line
			(start -0.12065 -0.2794)
			(end -0.12065 -0.3048)
			(stroke
				(width 0.1)
				(type default)
			)
			(layer "B.Fab")
		)
		(fp_line
			(start -0.12065 -0.3048)
			(end -0.67945 -0.3048)
			(stroke
				(width 0.1)
				(type default)
			)
			(layer "B.Fab")
		)
		(fp_line
			(start -0.67945 0.3048)
			(end -0.120396 0.3048)
			(stroke
				(width 0.1)
				(type default)
			)
			(layer "B.Fab")
		)
		(fp_line
			(start -0.67945 -0.3048)
			(end -0.67945 0.3048)
			(stroke
				(width 0.1)
				(type default)
			)
			(layer "B.Fab")
		)
		(pad "1" smd circle
			(at 0.40005 0)
			(size 0 0)
			(layers "B.Cu" "B.Mask" "B.Paste")
			(net "PVDDCR_CPU1_P0")
		)
		(pad "2" smd circle
			(at -0.40005 0)
			(size 0 0)
			(layers "B.Cu" "B.Mask" "B.Paste")
			(net "GND")
		)
	)
	(footprint ""
		(layer "B.Cu")
		(at 28.657804 -388.654036 90)
		(property "Reference" "PC6635_2"
			(at 0 0 90)
			(layer "B.SilkS")
			(hide yes)
			(effects
				(font
					(size 1.27 1.27)
				)
				(justify mirror)
			)
		)
		(property "Value" ""
			(at 0 0 90)
			(layer "B.Fab")
			(effects
				(font
					(size 1.27 1.27)
				)
				(justify mirror)
			)
		)
		(duplicate_pad_numbers_are_jumpers no)
		(fp_line
			(start 1.524 -0.762)
			(end -1.524 -0.762)
			(stroke
				(width 0.1524)
				(type default)
			)
			(layer "B.SilkS")
		)
		(fp_line
			(start -1.524 -0.762)
			(end -1.524 0.762)
			(stroke
				(width 0.1524)
				(type default)
			)
			(layer "B.SilkS")
		)
		(fp_line
			(start 1.524 0.762)
			(end 1.524 -0.762)
			(stroke
				(width 0.1524)
				(type default)
			)
			(layer "B.SilkS")
		)
		(fp_line
			(start -1.524 0.762)
			(end 1.524 0.762)
			(stroke
				(width 0.1524)
				(type default)
			)
			(layer "B.SilkS")
		)
		(fp_line
			(start 1.1049 -0.724916)
			(end 1.1049 0.724916)
			(stroke
				(width 0.1)
				(type default)
			)
			(layer "B.Fab")
		)
		(fp_line
			(start -1.1049 -0.724916)
			(end 1.1049 -0.724916)
			(stroke
				(width 0.1)
				(type default)
			)
			(layer "B.Fab")
		)
		(fp_line
			(start 1.1049 0.724916)
			(end -1.1049 0.724916)
			(stroke
				(width 0.1)
				(type default)
			)
			(layer "B.Fab")
		)
		(fp_line
			(start -1.1049 0.724916)
			(end -1.1049 -0.724916)
			(stroke
				(width 0.1)
				(type default)
			)
			(layer "B.Fab")
		)
		(pad "1" smd rect
			(at 0.889 0 90)
			(size 1.016 1.27)
			(layers "B.Cu" "B.Mask" "B.Paste")
			(net "SW_P12V_AUX_P0V9_RETIMER_CPU1_FLT")
		)
		(pad "2" smd rect
			(at -0.889 0 90)
			(size 1.016 1.27)
			(layers "B.Cu" "B.Mask" "B.Paste")
			(net "GND")
		)
	)
	(footprint ""
		(layer "B.Cu")
		(at 241.938048 -289.533838 -90)
		(property "Reference" "PR6501"
			(at 0 0 90)
			(layer "B.SilkS")
			(hide yes)
			(effects
				(font
					(size 1.27 1.27)
				)
				(justify mirror)
			)
		)
		(property "Value" ""
			(at 0 0 90)
			(layer "B.Fab")
			(effects
				(font
					(size 1.27 1.27)
				)
				(justify mirror)
			)
		)
		(duplicate_pad_numbers_are_jumpers no)
		(fp_line
			(start -0.7874 0.4064)
			(end 0.7874 0.4064)
			(stroke
				(width 0.1524)
				(type default)
			)
			(layer "B.SilkS")
		)
		(fp_line
			(start 0.7874 0.4064)
			(end 0.7874 -0.4064)
			(stroke
				(width 0.1524)
				(type default)
			)
			(layer "B.SilkS")
		)
		(fp_line
			(start -0.7874 -0.4064)
			(end -0.7874 0.4064)
			(stroke
				(width 0.1524)
				(type default)
			)
			(layer "B.SilkS")
		)
		(fp_line
			(start 0.7874 -0.4064)
			(end -0.7874 -0.4064)
			(stroke
				(width 0.1524)
				(type default)
			)
			(layer "B.SilkS")
		)
		(fp_line
			(start -0.67945 0.3048)
			(end -0.120396 0.3048)
			(stroke
				(width 0.1)
				(type default)
			)
			(layer "B.Fab")
		)
		(fp_line
			(start -0.120396 0.3048)
			(end -0.120396 0.2794)
			(stroke
				(width 0.1)
				(type default)
			)
			(layer "B.Fab")
		)
		(fp_line
			(start 0.12065 0.3048)
			(end 0.67945 0.3048)
			(stroke
				(width 0.1)
				(type default)
			)
			(layer "B.Fab")
		)
		(fp_line
			(start 0.67945 0.3048)
			(end 0.67945 -0.305054)
			(stroke
				(width 0.1)
				(type default)
			)
			(layer "B.Fab")
		)
		(fp_line
			(start -0.120396 0.2794)
			(end 0.12065 0.2794)
			(stroke
				(width 0.1)
				(type default)
			)
			(layer "B.Fab")
		)
		(fp_line
			(start 0.12065 0.2794)
			(end 0.12065 0.3048)
			(stroke
				(width 0.1)
				(type default)
			)
			(layer "B.Fab")
		)
		(fp_line
			(start -0.12065 -0.2794)
			(end -0.12065 -0.3048)
			(stroke
				(width 0.1)
				(type default)
			)
			(layer "B.Fab")
		)
		(fp_line
			(start 0.12065 -0.2794)
			(end -0.12065 -0.2794)
			(stroke
				(width 0.1)
				(type default)
			)
			(layer "B.Fab")
		)
		(fp_line
			(start -0.67945 -0.3048)
			(end -0.67945 0.3048)
			(stroke
				(width 0.1)
				(type default)
			)
			(layer "B.Fab")
		)
		(fp_line
			(start -0.12065 -0.3048)
			(end -0.67945 -0.3048)
			(stroke
				(width 0.1)
				(type default)
			)
			(layer "B.Fab")
		)
		(fp_line
			(start 0.12065 -0.305054)
			(end 0.12065 -0.2794)
			(stroke
				(width 0.1)
				(type default)
			)
			(layer "B.Fab")
		)
		(fp_line
			(start 0.67945 -0.305054)
			(end 0.12065 -0.305054)
			(stroke
				(width 0.1)
				(type default)
			)
			(layer "B.Fab")
		)
		(pad "1" smd circle
			(at 0.40005 0 90)
			(size 0 0)
			(layers "B.Cu" "B.Mask" "B.Paste")
			(net "P3V3_AUX")
		)
		(pad "2" smd circle
			(at -0.40005 0 90)
			(size 0 0)
			(layers "B.Cu" "B.Mask" "B.Paste")
			(net "P1V8_RETIMER_CPU0_VCC")
		)
	)
)
